G04 ================== begin FILE IDENTIFICATION RECORD ==================*
G04 Layout Name:  15750-1.brd*
G04 Film Name:    DP_REF_L1*
G04 File Format:  Gerber RS274X*
G04 File Origin:  Cadence Allegro 16.5-S056*
G04 Origin Date:  Fri Dec 30 13:21:41 2016*
G04 *
G04 Layer:  BOARD GEOMETRY/DP_REF_L1_TBL*
G04 Layer:  BOARD GEOMETRY/DP_REF_L1_TOP*
G04 Layer:  BOARD GEOMETRY/PANEL_OUTLINE*
G04 *
G04 Offset:    (0.00 0.00)*
G04 Mirror:    No*
G04 Mode:      Positive*
G04 Rotation:  0*
G04 FullContactRelief:  No*
G04 UndefLineWidth:     6.00*
G04 ================== end FILE IDENTIFICATION RECORD ====================*
%FSLAX35Y35*MOIN*%
%IR0*IPPOS*OFA0.00000B0.00000*MIA0B0*SFA1.00000B1.00000*%
%ADD10C,.02*%
%ADD11C,.006*%
%ADD12C,.00538*%
G75*
%LPD*%
G75*
G54D10*
G01X772440Y279160D02*
X1524940D01*
G01X772440Y348460D02*
Y279160D01*
G01Y313810D02*
X1524940D01*
G01X772440Y348460D02*
X1524940D01*
G01X947440D02*
Y279160D01*
G01X1209940Y348460D02*
Y279160D01*
G01X1314940Y348460D02*
Y279160D01*
G01X1524940Y348460D02*
Y279160D01*
G54D11*
G01X6549Y-157539D02*
Y-175039D01*
G01X1527Y-157539D02*
X11571D01*
G01X20337Y-175039D02*
Y-157539D01*
G01Y-165997D02*
X21429Y-164539D01*
X22521Y-163664D01*
X24267Y-163373D01*
X25577Y-163664D01*
X27106Y-164831D01*
X27761Y-166581D01*
Y-175039D01*
G01X41549Y-163373D02*
Y-175039D01*
G01Y-158706D02*
X41112Y-158414D01*
Y-157831D01*
X41549Y-157539D01*
X41986Y-157831D01*
Y-158414D01*
X41549Y-158706D01*
G01X55774Y-172998D02*
X56866Y-174164D01*
X58394Y-175039D01*
X59704D01*
X61014Y-174456D01*
X61887Y-173581D01*
X62324Y-172415D01*
X62106Y-170664D01*
X61232Y-169789D01*
X57302Y-168039D01*
X56429Y-165997D01*
X56866Y-164539D01*
X57739Y-163664D01*
X59049Y-163373D01*
X60359Y-163664D01*
X61669Y-164539D01*
G01X90992Y-179414D02*
X92521Y-180581D01*
X94267Y-180872D01*
X95795Y-180581D01*
X97106Y-179123D01*
X97979Y-177081D01*
Y-163373D01*
G01Y-165706D02*
X97106Y-164539D01*
X95795Y-163664D01*
X94267Y-163373D01*
X92521Y-163956D01*
X91429Y-165122D01*
X90555Y-167164D01*
X90119Y-169206D01*
X90337Y-170956D01*
X91211Y-172998D01*
X92521Y-174456D01*
X94267Y-175039D01*
X95577Y-174747D01*
X97106Y-173581D01*
X97979Y-172415D01*
G01X108274Y-167164D02*
X115261D01*
X114606Y-165122D01*
X113514Y-163956D01*
X111986Y-163373D01*
X110457Y-163664D01*
X109147Y-164539D01*
X108274Y-166581D01*
X107837Y-168331D01*
Y-170081D01*
X108274Y-171831D01*
X109366Y-173581D01*
X110676Y-174747D01*
X112204Y-175039D01*
X113732Y-174456D01*
X115261Y-172706D01*
G01X125992Y-175039D02*
Y-163373D01*
G01Y-165706D02*
X127084Y-164539D01*
X128176Y-163664D01*
X129704Y-163373D01*
X130795Y-163664D01*
X132106Y-164539D01*
G01X142619Y-175039D02*
Y-157539D01*
G01Y-166289D02*
X143711Y-164539D01*
X145021Y-163664D01*
X146331Y-163373D01*
X148295Y-163956D01*
X149606Y-165122D01*
X150479Y-167164D01*
Y-169497D01*
X150042Y-171831D01*
X149169Y-173581D01*
X147641Y-174747D01*
X146331Y-175039D01*
X145021Y-174747D01*
X143711Y-173873D01*
X142619Y-172415D01*
G01X160774Y-167164D02*
X167761D01*
X167106Y-165122D01*
X166014Y-163956D01*
X164486Y-163373D01*
X162957Y-163664D01*
X161647Y-164539D01*
X160774Y-166581D01*
X160337Y-168331D01*
Y-170081D01*
X160774Y-171831D01*
X161866Y-173581D01*
X163176Y-174747D01*
X164704Y-175039D01*
X166232Y-174456D01*
X167761Y-172706D01*
G01X178492Y-175039D02*
Y-163373D01*
G01Y-165706D02*
X179584Y-164539D01*
X180676Y-163664D01*
X182204Y-163373D01*
X183295Y-163664D01*
X184606Y-164539D01*
G01X216549Y-163373D02*
Y-175039D01*
G01Y-158706D02*
X216112Y-158414D01*
Y-157831D01*
X216549Y-157539D01*
X216986Y-157831D01*
Y-158414D01*
X216549Y-158706D01*
G01X230774Y-172998D02*
X231866Y-174164D01*
X233394Y-175039D01*
X234704D01*
X236014Y-174456D01*
X236887Y-173581D01*
X237324Y-172415D01*
X237106Y-170664D01*
X236232Y-169789D01*
X232302Y-168039D01*
X231429Y-165997D01*
X231866Y-164539D01*
X232739Y-163664D01*
X234049Y-163373D01*
X235359Y-163664D01*
X236669Y-164539D01*
G01X265555Y-179414D02*
X267084Y-180581D01*
X268394Y-180872D01*
X270141Y-180289D01*
X271451Y-178831D01*
X272106Y-176205D01*
Y-163373D01*
G01Y-158706D02*
X271669Y-158414D01*
Y-157831D01*
X272106Y-157539D01*
X272542Y-157831D01*
Y-158414D01*
X272106Y-158706D01*
G01X282837Y-163373D02*
Y-171539D01*
X283711Y-173581D01*
X285021Y-174747D01*
X286549Y-175039D01*
X288077Y-174747D01*
X289387Y-173581D01*
X290261Y-171539D01*
G01Y-175039D02*
Y-163373D01*
G01X300774Y-172998D02*
X301866Y-174164D01*
X303394Y-175039D01*
X304704D01*
X306014Y-174456D01*
X306887Y-173581D01*
X307324Y-172415D01*
X307106Y-170664D01*
X306232Y-169789D01*
X302302Y-168039D01*
X301429Y-165997D01*
X301866Y-164539D01*
X302739Y-163664D01*
X304049Y-163373D01*
X305359Y-163664D01*
X306669Y-164539D01*
G01X321549Y-157539D02*
Y-175039D01*
G01X318492Y-163373D02*
X324606D01*
G01X355239Y-175039D02*
Y-160164D01*
X355676Y-158706D01*
X356549Y-157831D01*
X357859Y-157539D01*
X359169Y-158122D01*
X359824Y-159581D01*
G01X357204Y-164539D02*
X352837D01*
G01X374049Y-175039D02*
X372739Y-174747D01*
X371429Y-173581D01*
X370555Y-171539D01*
X370119Y-169206D01*
X370555Y-166872D01*
X371429Y-164831D01*
X372739Y-163664D01*
X374049Y-163373D01*
X375359Y-163664D01*
X376669Y-164831D01*
X377542Y-166872D01*
X377761Y-169206D01*
X377542Y-171539D01*
X376669Y-173581D01*
X375359Y-174747D01*
X374049Y-175039D01*
G01X388492D02*
Y-163373D01*
G01Y-165706D02*
X389584Y-164539D01*
X390676Y-163664D01*
X392204Y-163373D01*
X393295Y-163664D01*
X394606Y-164539D01*
G01X421964Y-180289D02*
X423274Y-180872D01*
X425021Y-180289D01*
X426112Y-179123D01*
X426986Y-177664D01*
X428295Y-172998D01*
X431134Y-163373D01*
G01X424147D02*
X428295Y-172998D01*
G01X444049Y-175039D02*
X442739Y-174747D01*
X441429Y-173581D01*
X440555Y-171539D01*
X440119Y-169206D01*
X440555Y-166872D01*
X441429Y-164831D01*
X442739Y-163664D01*
X444049Y-163373D01*
X445359Y-163664D01*
X446669Y-164831D01*
X447542Y-166872D01*
X447761Y-169206D01*
X447542Y-171539D01*
X446669Y-173581D01*
X445359Y-174747D01*
X444049Y-175039D01*
G01X457837Y-163373D02*
Y-171539D01*
X458711Y-173581D01*
X460021Y-174747D01*
X461549Y-175039D01*
X463077Y-174747D01*
X464387Y-173581D01*
X465261Y-171539D01*
G01Y-175039D02*
Y-163373D01*
G01X475992Y-175039D02*
Y-163373D01*
G01Y-165706D02*
X477084Y-164539D01*
X478176Y-163664D01*
X479704Y-163373D01*
X480795Y-163664D01*
X482106Y-164539D01*
G01X510992Y-175039D02*
Y-163373D01*
G01Y-165706D02*
X512084Y-164539D01*
X513176Y-163664D01*
X514704Y-163373D01*
X515795Y-163664D01*
X517106Y-164539D01*
G01X528274Y-167164D02*
X535261D01*
X534606Y-165122D01*
X533514Y-163956D01*
X531986Y-163373D01*
X530457Y-163664D01*
X529147Y-164539D01*
X528274Y-166581D01*
X527837Y-168331D01*
Y-170081D01*
X528274Y-171831D01*
X529366Y-173581D01*
X530676Y-174747D01*
X532204Y-175039D01*
X533732Y-174456D01*
X535261Y-172706D01*
G01X547739Y-175039D02*
Y-160164D01*
X548176Y-158706D01*
X549049Y-157831D01*
X550359Y-157539D01*
X551669Y-158122D01*
X552324Y-159581D01*
G01X549704Y-164539D02*
X545337D01*
G01X563274Y-167164D02*
X570261D01*
X569606Y-165122D01*
X568514Y-163956D01*
X566986Y-163373D01*
X565457Y-163664D01*
X564147Y-164539D01*
X563274Y-166581D01*
X562837Y-168331D01*
Y-170081D01*
X563274Y-171831D01*
X564366Y-173581D01*
X565676Y-174747D01*
X567204Y-175039D01*
X568732Y-174456D01*
X570261Y-172706D01*
G01X580992Y-175039D02*
Y-163373D01*
G01Y-165706D02*
X582084Y-164539D01*
X583176Y-163664D01*
X584704Y-163373D01*
X585795Y-163664D01*
X587106Y-164539D01*
G01X598274Y-167164D02*
X605261D01*
X604606Y-165122D01*
X603514Y-163956D01*
X601986Y-163373D01*
X600457Y-163664D01*
X599147Y-164539D01*
X598274Y-166581D01*
X597837Y-168331D01*
Y-170081D01*
X598274Y-171831D01*
X599366Y-173581D01*
X600676Y-174747D01*
X602204Y-175039D01*
X603732Y-174456D01*
X605261Y-172706D01*
G01X615337Y-175039D02*
Y-163373D01*
G01Y-166289D02*
X616211Y-164831D01*
X617521Y-163664D01*
X619267Y-163373D01*
X620795Y-163664D01*
X622106Y-164831D01*
X622761Y-166872D01*
Y-175039D01*
G01X640042Y-164831D02*
X638514Y-163664D01*
X637204Y-163373D01*
X635457Y-163956D01*
X634147Y-165122D01*
X633274Y-167164D01*
X633055Y-169206D01*
X633274Y-171248D01*
X634147Y-172998D01*
X635457Y-174456D01*
X637204Y-175039D01*
X638732Y-174456D01*
X640042Y-173289D01*
G01X650774Y-167164D02*
X657761D01*
X657106Y-165122D01*
X656014Y-163956D01*
X654486Y-163373D01*
X652957Y-163664D01*
X651647Y-164539D01*
X650774Y-166581D01*
X650337Y-168331D01*
Y-170081D01*
X650774Y-171831D01*
X651866Y-173581D01*
X653176Y-174747D01*
X654704Y-175039D01*
X656232Y-174456D01*
X657761Y-172706D01*
G01X689049Y-157539D02*
Y-175039D01*
G01X685992Y-163373D02*
X692106D01*
G01X706549Y-175039D02*
X705239Y-174747D01*
X703929Y-173581D01*
X703055Y-171539D01*
X702619Y-169206D01*
X703055Y-166872D01*
X703929Y-164831D01*
X705239Y-163664D01*
X706549Y-163373D01*
X707859Y-163664D01*
X709169Y-164831D01*
X710042Y-166872D01*
X710261Y-169206D01*
X710042Y-171539D01*
X709169Y-173581D01*
X707859Y-174747D01*
X706549Y-175039D01*
G01X740239D02*
Y-160164D01*
X740676Y-158706D01*
X741549Y-157831D01*
X742859Y-157539D01*
X744169Y-158122D01*
X744824Y-159581D01*
G01X742204Y-164539D02*
X737837D01*
G01X759049Y-163373D02*
Y-175039D01*
G01Y-158706D02*
X758612Y-158414D01*
Y-157831D01*
X759049Y-157539D01*
X759486Y-157831D01*
Y-158414D01*
X759049Y-158706D01*
G01X772837Y-175039D02*
Y-163373D01*
G01Y-166289D02*
X773711Y-164831D01*
X775021Y-163664D01*
X776767Y-163373D01*
X778295Y-163664D01*
X779606Y-164831D01*
X780261Y-166872D01*
Y-175039D01*
G01X797979Y-157539D02*
Y-175039D01*
G01Y-172415D02*
X797106Y-173873D01*
X795795Y-174747D01*
X794267Y-175039D01*
X792521Y-174456D01*
X791211Y-172998D01*
X790337Y-171248D01*
X790119Y-169206D01*
X790337Y-167164D01*
X791211Y-165414D01*
X792521Y-163956D01*
X794267Y-163373D01*
X795795Y-163664D01*
X796887Y-164248D01*
X797979Y-165414D01*
G01X829049Y-157539D02*
Y-175039D01*
G01X825992Y-163373D02*
X832106D01*
G01X842837Y-175039D02*
Y-157539D01*
G01Y-165997D02*
X843929Y-164539D01*
X845021Y-163664D01*
X846767Y-163373D01*
X848077Y-163664D01*
X849606Y-164831D01*
X850261Y-166581D01*
Y-175039D01*
G01X860774Y-167164D02*
X867761D01*
X867106Y-165122D01*
X866014Y-163956D01*
X864486Y-163373D01*
X862957Y-163664D01*
X861647Y-164539D01*
X860774Y-166581D01*
X860337Y-168331D01*
Y-170081D01*
X860774Y-171831D01*
X861866Y-173581D01*
X863176Y-174747D01*
X864704Y-175039D01*
X866232Y-174456D01*
X867761Y-172706D01*
G01X894246Y-175039D02*
Y-157539D01*
X898612D01*
X900359Y-158414D01*
X901669Y-159581D01*
X902761Y-161330D01*
X903634Y-163373D01*
X903852Y-166289D01*
X903634Y-169206D01*
X902761Y-171248D01*
X901669Y-172998D01*
X900359Y-174164D01*
X898612Y-175039D01*
X894246D01*
G01X912182D02*
Y-157539D01*
X917422D01*
X919169Y-158414D01*
X920479Y-160456D01*
X920916Y-162789D01*
X920479Y-165122D01*
X919387Y-166872D01*
X917422Y-167748D01*
X912182D01*
G01X951549Y-163373D02*
Y-175039D01*
G01Y-158706D02*
X951112Y-158414D01*
Y-157831D01*
X951549Y-157539D01*
X951986Y-157831D01*
Y-158414D01*
X951549Y-158706D01*
G01X962499Y-175039D02*
Y-163373D01*
G01Y-166581D02*
X963154Y-165122D01*
X964246Y-163956D01*
X965774Y-163373D01*
X967302Y-163956D01*
X968394Y-165122D01*
X969049Y-166581D01*
Y-175039D01*
G01Y-166581D02*
X969704Y-165122D01*
X970795Y-163956D01*
X972324Y-163373D01*
X973852Y-163956D01*
X974944Y-165122D01*
X975599Y-166872D01*
Y-175039D01*
G01X982619Y-180872D02*
Y-163373D01*
G01Y-165997D02*
X983711Y-164539D01*
X984802Y-163664D01*
X986549Y-163373D01*
X988077Y-163664D01*
X989606Y-165122D01*
X990261Y-167164D01*
X990479Y-169206D01*
X990261Y-171248D01*
X989606Y-173289D01*
X988295Y-174456D01*
X986549Y-175039D01*
X985021Y-174747D01*
X983492Y-173873D01*
X982619Y-172706D01*
G01X1000774Y-167164D02*
X1007761D01*
X1007106Y-165122D01*
X1006014Y-163956D01*
X1004486Y-163373D01*
X1002957Y-163664D01*
X1001647Y-164539D01*
X1000774Y-166581D01*
X1000337Y-168331D01*
Y-170081D01*
X1000774Y-171831D01*
X1001866Y-173581D01*
X1003176Y-174747D01*
X1004704Y-175039D01*
X1006232Y-174456D01*
X1007761Y-172706D01*
G01X1025479Y-157539D02*
Y-175039D01*
G01Y-172415D02*
X1024606Y-173873D01*
X1023295Y-174747D01*
X1021767Y-175039D01*
X1020021Y-174456D01*
X1018711Y-172998D01*
X1017837Y-171248D01*
X1017619Y-169206D01*
X1017837Y-167164D01*
X1018711Y-165414D01*
X1020021Y-163956D01*
X1021767Y-163373D01*
X1023295Y-163664D01*
X1024387Y-164248D01*
X1025479Y-165414D01*
G01X1042979Y-175039D02*
Y-163373D01*
G01Y-165414D02*
X1042106Y-164248D01*
X1040795Y-163664D01*
X1039267Y-163373D01*
X1037739Y-163956D01*
X1036429Y-165122D01*
X1035555Y-166872D01*
X1035119Y-169206D01*
X1035555Y-171539D01*
X1036429Y-173289D01*
X1037739Y-174456D01*
X1039267Y-175039D01*
X1040795Y-174747D01*
X1042106Y-173873D01*
X1042979Y-172706D01*
G01X1052837Y-175039D02*
Y-163373D01*
G01Y-166289D02*
X1053711Y-164831D01*
X1055021Y-163664D01*
X1056767Y-163373D01*
X1058295Y-163664D01*
X1059606Y-164831D01*
X1060261Y-166872D01*
Y-175039D01*
G01X1077542Y-164831D02*
X1076014Y-163664D01*
X1074704Y-163373D01*
X1072957Y-163956D01*
X1071647Y-165122D01*
X1070774Y-167164D01*
X1070555Y-169206D01*
X1070774Y-171248D01*
X1071647Y-172998D01*
X1072957Y-174456D01*
X1074704Y-175039D01*
X1076232Y-174456D01*
X1077542Y-173289D01*
G01X1088274Y-167164D02*
X1095261D01*
X1094606Y-165122D01*
X1093514Y-163956D01*
X1091986Y-163373D01*
X1090457Y-163664D01*
X1089147Y-164539D01*
X1088274Y-166581D01*
X1087837Y-168331D01*
Y-170081D01*
X1088274Y-171831D01*
X1089366Y-173581D01*
X1090676Y-174747D01*
X1092204Y-175039D01*
X1093732Y-174456D01*
X1095261Y-172706D01*
G01X1126549Y-157539D02*
Y-175039D01*
G01X1123492Y-163373D02*
X1129606D01*
G01X1140992Y-175039D02*
Y-163373D01*
G01Y-165706D02*
X1142084Y-164539D01*
X1143176Y-163664D01*
X1144704Y-163373D01*
X1145795Y-163664D01*
X1147106Y-164539D01*
G01X1165479Y-175039D02*
Y-163373D01*
G01Y-165414D02*
X1164606Y-164248D01*
X1163295Y-163664D01*
X1161767Y-163373D01*
X1160239Y-163956D01*
X1158929Y-165122D01*
X1158055Y-166872D01*
X1157619Y-169206D01*
X1158055Y-171539D01*
X1158929Y-173289D01*
X1160239Y-174456D01*
X1161767Y-175039D01*
X1163295Y-174747D01*
X1164606Y-173873D01*
X1165479Y-172706D01*
G01X1182542Y-164831D02*
X1181014Y-163664D01*
X1179704Y-163373D01*
X1177957Y-163956D01*
X1176647Y-165122D01*
X1175774Y-167164D01*
X1175555Y-169206D01*
X1175774Y-171248D01*
X1176647Y-172998D01*
X1177957Y-174456D01*
X1179704Y-175039D01*
X1181232Y-174456D01*
X1182542Y-173289D01*
G01X1193274Y-167164D02*
X1200261D01*
X1199606Y-165122D01*
X1198514Y-163956D01*
X1196986Y-163373D01*
X1195457Y-163664D01*
X1194147Y-164539D01*
X1193274Y-166581D01*
X1192837Y-168331D01*
Y-170081D01*
X1193274Y-171831D01*
X1194366Y-173581D01*
X1195676Y-174747D01*
X1197204Y-175039D01*
X1198732Y-174456D01*
X1200261Y-172706D01*
G01X1210774Y-172998D02*
X1211866Y-174164D01*
X1213394Y-175039D01*
X1214704D01*
X1216014Y-174456D01*
X1216887Y-173581D01*
X1217324Y-172415D01*
X1217106Y-170664D01*
X1216232Y-169789D01*
X1212302Y-168039D01*
X1211429Y-165997D01*
X1211866Y-164539D01*
X1212739Y-163664D01*
X1214049Y-163373D01*
X1215359Y-163664D01*
X1216669Y-164539D01*
G01X1249049Y-163373D02*
Y-175039D01*
G01Y-158706D02*
X1248612Y-158414D01*
Y-157831D01*
X1249049Y-157539D01*
X1249486Y-157831D01*
Y-158414D01*
X1249049Y-158706D01*
G01X1262837Y-175039D02*
Y-163373D01*
G01Y-166289D02*
X1263711Y-164831D01*
X1265021Y-163664D01*
X1266767Y-163373D01*
X1268295Y-163664D01*
X1269606Y-164831D01*
X1270261Y-166872D01*
Y-175039D01*
G01X1301549D02*
Y-157539D01*
G01X1322979Y-175039D02*
Y-163373D01*
G01Y-165414D02*
X1322106Y-164248D01*
X1320795Y-163664D01*
X1319267Y-163373D01*
X1317739Y-163956D01*
X1316429Y-165122D01*
X1315555Y-166872D01*
X1315119Y-169206D01*
X1315555Y-171539D01*
X1316429Y-173289D01*
X1317739Y-174456D01*
X1319267Y-175039D01*
X1320795Y-174747D01*
X1322106Y-173873D01*
X1322979Y-172706D01*
G01X1331964Y-180289D02*
X1333274Y-180872D01*
X1335021Y-180289D01*
X1336112Y-179123D01*
X1336986Y-177664D01*
X1338295Y-172998D01*
X1341134Y-163373D01*
G01X1334147D02*
X1338295Y-172998D01*
G01X1350774Y-167164D02*
X1357761D01*
X1357106Y-165122D01*
X1356014Y-163956D01*
X1354486Y-163373D01*
X1352957Y-163664D01*
X1351647Y-164539D01*
X1350774Y-166581D01*
X1350337Y-168331D01*
Y-170081D01*
X1350774Y-171831D01*
X1351866Y-173581D01*
X1353176Y-174747D01*
X1354704Y-175039D01*
X1356232Y-174456D01*
X1357761Y-172706D01*
G01X1368492Y-175039D02*
Y-163373D01*
G01Y-165706D02*
X1369584Y-164539D01*
X1370676Y-163664D01*
X1372204Y-163373D01*
X1373295Y-163664D01*
X1374606Y-164539D01*
G01X1402182Y-157539D02*
Y-175039D01*
X1410916D01*
G01X1424049D02*
Y-157539D01*
X1421429Y-161039D01*
G01Y-175039D02*
X1426669D01*
G01X1441549Y-175622D02*
X1441112Y-175331D01*
Y-174747D01*
X1441549Y-174456D01*
X1441986Y-174747D01*
Y-175331D01*
X1441549Y-175622D01*
G01X-1Y-113228D02*
Y-117165D01*
G03X7873Y-125039I7874J0D01*
G01X714566D01*
G03X722440Y-117165I0J7874D01*
G01Y-113228D01*
G01X1968Y40473D02*
X9842D01*
G02X11811Y38504I0J-1969D01*
G01Y-16772D01*
G02X9842Y-18740I-1969J1D01*
G01X1968D01*
G03X0Y-20709I0J-1968D01*
G01Y-97480D01*
G03X7874Y-105354I7874J0D01*
G01X341535D01*
G03X349409Y-97480I0J7874D01*
G01Y-15748D01*
G03X341535Y-7874I-7874J0D01*
G01X141338D01*
G02X133464Y0I0J7874D01*
G01Y250197D01*
G03X125590Y258071I-7874J0D01*
G01X1968D01*
G03X0Y256102I0J-1968D01*
G01Y236673D01*
G03X1968Y234705I1968J0D01*
G01X28346D01*
G02X30315Y232736I0J-1969D01*
G01Y216004D01*
G02X28346Y214036I-1968J0D01*
G01X23228D01*
G03X21259Y212067I0J-1969D01*
G01Y86752D01*
G03X23228Y84784I1969J1D01*
G01X28346D01*
G02X30315Y82815I0J-1969D01*
G01Y66083D01*
G02X28346Y64114I-1969J0D01*
G01X1968D01*
G03X0Y62146I0J-1968D01*
G01Y42441D01*
G03X1968Y40473I1968J0D01*
G01X-1Y-113228D02*
X13591D01*
G01X347441Y217598D02*
X339567D01*
G02X337598Y219567I0J1969D01*
G01Y274843D01*
G02X339567Y276811I1969J-1D01*
G01X347441D01*
G03X349409Y278780I0J1968D01*
G01Y355551D01*
G03X341535Y363425I-7874J0D01*
G01X7874D01*
G03X0Y355551I0J-7874D01*
G01Y273819D01*
G03X7874Y265945I7874J0D01*
G01X208071D01*
G02X215945Y258071I0J-7874D01*
G01Y7874D01*
G03X223819Y0I7874J0D01*
G01X347441D01*
G03X349409Y1969I0J1968D01*
G01Y21398D01*
G03X347441Y23366I-1968J0D01*
G01X321063D01*
G02X319094Y25335I0J1969D01*
G01Y42067D01*
G02X321063Y44035I1969J-1D01*
G01X326181D01*
G03X328150Y46004I0J1969D01*
G01Y171319D01*
G03X326181Y173287I-1968J0D01*
G01X321063D01*
G02X319094Y175256I0J1969D01*
G01Y191988D01*
G02X321063Y193957I1969J0D01*
G01X347441D01*
G03X349409Y195925I0J1968D01*
G01Y215630D01*
G03X347441Y217598I-1968J0D01*
G01X245745Y383110D02*
X7874D01*
G03X0Y375236I0J-7874D01*
G01Y371299D01*
G01D02*
X13591D01*
G01Y-113228D02*
G03Y-105354I0J3937D01*
G01Y258071D02*
G03Y265945I0J3937D01*
G01Y363425D02*
G03Y371299I0J3937D01*
G01X38787Y-113228D02*
X237000D01*
G01X38787Y-105354D02*
G03Y-113228I1J-3937D01*
G01Y265945D02*
G03Y258071I1J-3937D01*
G01X237000Y371299D02*
X38787D01*
G01D02*
G03Y363425I1J-3937D01*
G01X141338Y116437D02*
G03X133464I-3937J0D01*
G01Y141634D02*
G03X141338I3937J0D01*
G01Y0D02*
Y116437D01*
G01X162106Y0D02*
X141337D01*
G01X141338Y141634D02*
Y258071D01*
G01D02*
X162106D01*
G01Y-7874D02*
G03Y0I0J3937D01*
G01X179626Y62719D02*
G03X171044I-4291J0D01*
G03X179626I4291J0D01*
G01Y189063D02*
G03X171044Y189062I-4291J0D01*
G03X179626Y189063I4291J1D01*
G01X162106Y258071D02*
G03Y265945I0J3937D01*
G01X187302Y0D02*
G03Y-7874I1J-3937D01*
G01X208071Y0D02*
X187302D01*
G01Y265945D02*
G03Y258071I1J-3937D01*
G01D02*
X208071D01*
G01X207913Y0D02*
X208071D01*
G01Y116437D02*
Y0D01*
G01X215945Y116437D02*
G03X208071I-3937J0D01*
G01Y141634D02*
G03X215945I3937J0D01*
G01X208071Y258071D02*
Y141634D01*
G01X237000Y-113228D02*
G03Y-105354I0J3937D01*
G01Y363425D02*
G03Y371299I0J3937D01*
G01X245745Y383110D02*
G03X253619I3937J0D01*
G01X722440Y371299D02*
Y375236D01*
G03X714566Y383110I-7874J0D01*
G01X253619D01*
G01X262196Y-113228D02*
X460244D01*
G01X262196Y-105354D02*
G03Y-113228I0J-3937D01*
G01Y371299D02*
X460244D01*
G01X262196D02*
G03Y363425I0J-3937D01*
G01X310621Y-7874D02*
G03Y0I0J3937D01*
G01X335817D02*
G03Y-7874I1J-3937D01*
G01X353346Y-47481D02*
G03X349409Y-51418I0J-3937D01*
G01Y-20709D02*
G03X353346Y-24646I3937J0D01*
G01Y282717D02*
G03X349409Y278780I0J-3937D01*
G01Y309489D02*
G03X353346Y305552I3937J0D01*
G01Y-47481D02*
X369094D01*
G01X373031Y-51418D02*
G03X369094Y-47481I-3937J0D01*
G01X353346Y-24646D02*
X369094D01*
G01D02*
G03X373031Y-20709I0J3937D01*
G01X353346Y282717D02*
X369094D01*
G01X373031Y278780D02*
G03X369094Y282717I-3937J0D01*
G01X353346Y305552D02*
X369094D01*
G01D02*
G03X373031Y309489I0J3937D01*
G01X374999Y40473D02*
X382873D01*
G02X384842Y38504I0J-1969D01*
G01Y-16772D01*
G02X382873Y-18740I-1969J1D01*
G01X374999D01*
G03X373031Y-20709I0J-1968D01*
G01Y-97480D01*
G03X380905Y-105354I7874J0D01*
G01X714566D01*
G03X722440Y-97480I0J7874D01*
G01Y-15748D01*
G03X714566Y-7874I-7874J0D01*
G01X514369D01*
G02X506495Y0I0J7874D01*
G01Y250197D01*
G03X498621Y258071I-7874J0D01*
G01X374999D01*
G03X373031Y256102I0J-1968D01*
G01Y236673D01*
G03X374999Y234705I1968J0D01*
G01X401377D01*
G02X403346Y232736I0J-1969D01*
G01Y216004D01*
G02X401377Y214036I-1968J0D01*
G01X396259D01*
G03X394290Y212067I0J-1969D01*
G01Y86752D01*
G03X396259Y84784I1969J1D01*
G01X401377D01*
G02X403346Y82815I0J-1969D01*
G01Y66083D01*
G02X401377Y64114I-1969J0D01*
G01X374999D01*
G03X373031Y62146I0J-1968D01*
G01Y42441D01*
G03X374999Y40473I1968J0D01*
G01X720472Y217598D02*
X712598D01*
G02X710629Y219567I0J1969D01*
G01Y274843D01*
G02X712598Y276811I1969J-1D01*
G01X720472D01*
G03X722440Y278780I0J1968D01*
G01Y355551D01*
G03X714566Y363425I-7874J0D01*
G01X380905D01*
G03X373031Y355551I0J-7874D01*
G01Y273819D01*
G03X380905Y265945I7874J0D01*
G01X581102D01*
G02X588976Y258071I0J-7874D01*
G01Y7874D01*
G03X596850Y0I7874J0D01*
G01X720472D01*
G03X722440Y1969I0J1968D01*
G01Y21398D01*
G03X720472Y23366I-1968J0D01*
G01X694094D01*
G02X692125Y25335I0J1969D01*
G01Y42067D01*
G02X694094Y44035I1969J-1D01*
G01X699212D01*
G03X701181Y46004I0J1969D01*
G01Y171319D01*
G03X699212Y173287I-1969J-1D01*
G01X694094D01*
G02X692125Y175256I0J1969D01*
G01Y191988D01*
G02X694094Y193957I1969J0D01*
G01X720472D01*
G03X722440Y195925I0J1968D01*
G01Y215630D01*
G03X720472Y217598I-1968J0D01*
G01X386622Y258071D02*
G03Y265945I0J3937D01*
G01X411819D02*
G03Y258071I0J-3937D01*
G01X460244Y-113228D02*
G03Y-105354I0J3937D01*
G01Y363425D02*
G03Y371299I0J3937D01*
G01X485441Y-105354D02*
G03Y-113228I0J-3937D01*
G01Y371299D02*
G03Y363425I0J-3937D01*
G01Y-113228D02*
X683652D01*
G01X485441Y371299D02*
X683652D01*
G01X514369Y0D02*
Y116437D01*
G01X535137Y0D02*
X514369D01*
G01Y116437D02*
G03X506494I-3937J0D01*
G01Y141634D02*
G03X514369I3937J0D01*
G01D02*
Y258071D01*
G01D02*
X535137D01*
G01Y-7874D02*
G03Y0I0J3937D01*
G01X551396Y69008D02*
G03X542813I-4291J0D01*
G03X551396I4291J0D01*
G01Y195351D02*
G03X542813Y195352I-4292J0D01*
G03X551396Y195351I4291J-1D01*
G01X535137Y258071D02*
G03Y265945I0J3937D01*
G01X560333Y0D02*
G03Y-7874I1J-3937D01*
G01X581102Y0D02*
X560333D01*
G01Y265945D02*
G03Y258071I1J-3937D01*
G01D02*
X581102D01*
G01Y116437D02*
Y0D01*
G01X588976Y116437D02*
G03X581102I-3937J0D01*
G01Y141634D02*
G03X588976I3937J0D01*
G01X581102Y258071D02*
Y141634D01*
G01X683652Y-113228D02*
G03Y-105354I0J3937D01*
G01Y-7874D02*
G03Y0I0J3937D01*
G01Y363425D02*
G03Y371299I0J3937D01*
G01X708848Y-113228D02*
X722440D01*
G01X708848Y-105354D02*
G03Y-113228I1J-3937D01*
G01Y0D02*
G03Y-7874I1J-3937D01*
G01Y371299D02*
X722440D01*
G01X708848D02*
G03Y363425I1J-3937D01*
G01X774187Y358210D02*
Y375710D01*
X778553D01*
X780300Y374835D01*
X781610Y373668D01*
X782702Y371919D01*
X783575Y369876D01*
X783793Y366960D01*
X783575Y364043D01*
X782702Y362001D01*
X781610Y360251D01*
X780300Y359085D01*
X778553Y358210D01*
X774187D01*
G01X792123D02*
Y375710D01*
X797363D01*
X799110Y374835D01*
X800420Y372793D01*
X800857Y370460D01*
X800420Y368127D01*
X799328Y366377D01*
X797363Y365501D01*
X792123D01*
G01X828870Y375710D02*
X834110D01*
G01X831490D02*
Y358210D01*
G01X828870D02*
X834110D01*
G01X843313D02*
Y375710D01*
X848990Y361127D01*
X854667Y375710D01*
Y358210D01*
G01X862123D02*
Y375710D01*
X867363D01*
X869110Y374835D01*
X870420Y372793D01*
X870857Y370460D01*
X870420Y368127D01*
X869328Y366377D01*
X867363Y365501D01*
X862123D01*
G01X888357Y358210D02*
X879623D01*
Y375710D01*
X888357D01*
G01X884863Y367252D02*
X879623D01*
G01X896687Y358210D02*
Y375710D01*
X901053D01*
X902800Y374835D01*
X904110Y373668D01*
X905202Y371919D01*
X906075Y369876D01*
X906293Y366960D01*
X906075Y364043D01*
X905202Y362001D01*
X904110Y360251D01*
X902800Y359085D01*
X901053Y358210D01*
X896687D01*
G01X913531D02*
X918990Y375710D01*
X924449Y358210D01*
G01X922483Y364335D02*
X915496D01*
G01X931468Y358210D02*
Y375710D01*
X941512Y358210D01*
Y375710D01*
G01X958793Y374251D02*
X957483Y375127D01*
X955955Y375710D01*
X954208D01*
X952243Y374835D01*
X950715Y373377D01*
X949623Y371626D01*
X948750Y368710D01*
X948531Y366085D01*
X948968Y363460D01*
X949623Y361710D01*
X950933Y359960D01*
X952462Y358793D01*
X953990Y358210D01*
X955518D01*
X957047Y358793D01*
X958357Y359668D01*
X959449Y360834D01*
G01X975857Y358210D02*
X967123D01*
Y375710D01*
X975857D01*
G01X972363Y367252D02*
X967123D01*
G01X1006490Y375710D02*
Y358210D01*
G01X1001468Y375710D02*
X1011512D01*
G01X1018531Y358210D02*
X1023990Y375710D01*
X1029449Y358210D01*
G01X1027483Y364335D02*
X1020496D01*
G01X1043236Y367543D02*
X1044110Y368418D01*
X1044765Y369876D01*
X1045202Y371919D01*
X1044765Y373668D01*
X1043892Y374835D01*
X1042363Y375710D01*
X1036468D01*
Y358210D01*
X1043673D01*
X1045202Y359376D01*
X1046075Y361127D01*
X1046512Y363168D01*
X1046075Y365210D01*
X1044765Y366960D01*
X1043236Y367543D01*
X1036468D01*
G01X1054623Y375710D02*
Y358210D01*
X1063357D01*
G01X1080857D02*
X1072123D01*
Y375710D01*
X1080857D01*
G01X1077363Y367252D02*
X1072123D01*
G01X1093990Y357627D02*
X1093553Y357918D01*
Y358502D01*
X1093990Y358793D01*
X1094427Y358502D01*
Y357918D01*
X1093990Y357627D01*
G01Y365501D02*
X1093553Y365793D01*
Y366377D01*
X1093990Y366668D01*
X1094427Y366377D01*
Y365793D01*
X1093990Y365501D01*
G01X1124623Y375710D02*
Y358210D01*
X1133357D01*
G01X1146490D02*
Y375710D01*
X1143870Y372210D01*
G01Y358210D02*
X1149110D01*
G01X796070Y341060D02*
X801310D01*
G01X798690D02*
Y323560D01*
G01X796070D02*
X801310D01*
G01X810513D02*
Y341060D01*
X816190Y326477D01*
X821867Y341060D01*
Y323560D01*
G01X829323D02*
Y341060D01*
X834563D01*
X836310Y340185D01*
X837620Y338143D01*
X838057Y335810D01*
X837620Y333477D01*
X836528Y331727D01*
X834563Y330851D01*
X829323D01*
G01X850098Y317727D02*
X847915Y320643D01*
X846823Y323560D01*
Y335226D01*
X847915Y338143D01*
X850098Y341060D01*
G01X868690Y323560D02*
X866943Y323852D01*
X865415Y325018D01*
X864105Y326768D01*
X863231Y328810D01*
X862795Y331143D01*
Y333477D01*
X863231Y335810D01*
X864105Y337852D01*
X865415Y339601D01*
X866943Y340768D01*
X868690Y341060D01*
X870436Y340768D01*
X871965Y339601D01*
X873275Y337852D01*
X874149Y335810D01*
X874585Y333477D01*
Y331143D01*
X874149Y328810D01*
X873275Y326768D01*
X871965Y325018D01*
X870436Y323852D01*
X868690Y323560D01*
G01X882478D02*
Y341060D01*
G01Y332602D02*
X883570Y334060D01*
X884662Y334935D01*
X886408Y335226D01*
X887718Y334935D01*
X889247Y333768D01*
X889902Y332018D01*
Y323560D01*
G01X897140D02*
Y335226D01*
G01Y332018D02*
X897795Y333477D01*
X898887Y334643D01*
X900415Y335226D01*
X901943Y334643D01*
X903035Y333477D01*
X903690Y332018D01*
Y323560D01*
G01Y332018D02*
X904345Y333477D01*
X905436Y334643D01*
X906965Y335226D01*
X908493Y334643D01*
X909585Y333477D01*
X910240Y331727D01*
Y323560D01*
G01X922282Y317727D02*
X924465Y320643D01*
X925557Y323560D01*
Y335226D01*
X924465Y338143D01*
X922282Y341060D01*
G01X833690Y288910D02*
X835218Y289202D01*
X836965Y290076D01*
X838057Y291534D01*
X838493Y293577D01*
X838057Y295618D01*
X836747Y297368D01*
X834782Y298243D01*
X832598D01*
X831288Y298827D01*
X830196Y300285D01*
X829760Y302326D01*
X830415Y304368D01*
X831943Y305827D01*
X833690Y306410D01*
X835436Y305827D01*
X836965Y304368D01*
X837620Y302326D01*
X837183Y300285D01*
X836092Y298827D01*
X834782Y298243D01*
X832598D01*
X830633Y297368D01*
X829323Y295618D01*
X828887Y293577D01*
X829323Y291534D01*
X830415Y290076D01*
X832162Y289202D01*
X833690Y288910D01*
G01X846387Y291534D02*
X847696Y290076D01*
X849225Y289202D01*
X851190Y288910D01*
X853155Y289493D01*
X854683Y290660D01*
X855775Y292701D01*
X855993Y295035D01*
X855557Y297368D01*
X854465Y298827D01*
X852936Y299993D01*
X851408Y300285D01*
X849880Y299993D01*
X847915Y298827D01*
X848570Y306410D01*
X854465D01*
G01X868690Y288327D02*
X868253Y288618D01*
Y289202D01*
X868690Y289493D01*
X869127Y289202D01*
Y288618D01*
X868690Y288327D01*
G01X886190Y306410D02*
X884443Y305827D01*
X883133Y304368D01*
X882260Y302619D01*
X881605Y300285D01*
X881387Y297660D01*
X881605Y295035D01*
X882260Y292701D01*
X883133Y290951D01*
X884443Y289493D01*
X886190Y288910D01*
X887936Y289493D01*
X889247Y290951D01*
X890120Y292701D01*
X890775Y295035D01*
X890993Y297660D01*
X890775Y300285D01*
X890120Y302619D01*
X889247Y304368D01*
X887936Y305827D01*
X886190Y306410D01*
G01X984640Y341060D02*
X987696Y323560D01*
X991190Y341060D01*
X994683Y323560D01*
X997740Y341060D01*
G01X1006070D02*
X1011310D01*
G01X1008690D02*
Y323560D01*
G01X1006070D02*
X1011310D01*
G01X1021387D02*
Y341060D01*
X1025753D01*
X1027500Y340185D01*
X1028810Y339018D01*
X1029902Y337269D01*
X1030775Y335226D01*
X1030993Y332310D01*
X1030775Y329393D01*
X1029902Y327351D01*
X1028810Y325601D01*
X1027500Y324435D01*
X1025753Y323560D01*
X1021387D01*
G01X1043690Y341060D02*
Y323560D01*
G01X1038668Y341060D02*
X1048712D01*
G01X1056605Y323560D02*
Y341060D01*
G01X1065775D02*
Y323560D01*
G01Y332310D02*
X1056605D01*
G01X1077598Y317727D02*
X1075415Y320643D01*
X1074323Y323560D01*
Y335226D01*
X1075415Y338143D01*
X1077598Y341060D01*
G01X1089640Y323560D02*
Y335226D01*
G01Y332018D02*
X1090295Y333477D01*
X1091387Y334643D01*
X1092915Y335226D01*
X1094443Y334643D01*
X1095535Y333477D01*
X1096190Y332018D01*
Y323560D01*
G01Y332018D02*
X1096845Y333477D01*
X1097936Y334643D01*
X1099465Y335226D01*
X1100993Y334643D01*
X1102085Y333477D01*
X1102740Y331727D01*
Y323560D01*
G01X1113690Y335226D02*
Y323560D01*
G01Y339893D02*
X1113253Y340185D01*
Y340768D01*
X1113690Y341060D01*
X1114127Y340768D01*
Y340185D01*
X1113690Y339893D01*
G01X1131190Y323560D02*
Y341060D01*
G01X1145415Y325601D02*
X1146507Y324435D01*
X1148035Y323560D01*
X1149345D01*
X1150655Y324143D01*
X1151528Y325018D01*
X1151965Y326184D01*
X1151747Y327935D01*
X1150873Y328810D01*
X1146943Y330560D01*
X1146070Y332602D01*
X1146507Y334060D01*
X1147380Y334935D01*
X1148690Y335226D01*
X1150000Y334935D01*
X1151310Y334060D01*
G01X1167282Y317727D02*
X1169465Y320643D01*
X1170557Y323560D01*
Y335226D01*
X1169465Y338143D01*
X1167282Y341060D01*
G01X1012637Y291534D02*
X1013946Y290076D01*
X1015475Y289202D01*
X1017440Y288910D01*
X1019405Y289493D01*
X1020933Y290660D01*
X1022025Y292701D01*
X1022243Y295035D01*
X1021807Y297368D01*
X1020715Y298827D01*
X1019186Y299993D01*
X1017658Y300285D01*
X1016130Y299993D01*
X1014165Y298827D01*
X1014820Y306410D01*
X1020715D01*
G01X1034940Y288327D02*
X1034503Y288618D01*
Y289202D01*
X1034940Y289493D01*
X1035377Y289202D01*
Y288618D01*
X1034940Y288327D01*
G01X1047637Y292410D02*
X1048946Y290368D01*
X1050693Y289202D01*
X1052658Y288910D01*
X1054405Y289202D01*
X1056152Y290660D01*
X1057243Y292410D01*
X1057462Y294160D01*
X1057025Y296201D01*
X1055497Y297660D01*
X1053968Y298243D01*
X1052003D01*
G01X1053968D02*
X1055278Y299118D01*
X1056370Y300576D01*
X1056807Y302326D01*
X1056370Y304077D01*
X1055278Y305535D01*
X1053313Y306410D01*
X1051348Y306118D01*
X1049383Y304951D01*
G01X1069940Y288910D02*
X1071468Y289202D01*
X1073215Y290076D01*
X1074307Y291534D01*
X1074743Y293577D01*
X1074307Y295618D01*
X1072997Y297368D01*
X1071032Y298243D01*
X1068848D01*
X1067538Y298827D01*
X1066446Y300285D01*
X1066010Y302326D01*
X1066665Y304368D01*
X1068193Y305827D01*
X1069940Y306410D01*
X1071686Y305827D01*
X1073215Y304368D01*
X1073870Y302326D01*
X1073433Y300285D01*
X1072342Y298827D01*
X1071032Y298243D01*
X1068848D01*
X1066883Y297368D01*
X1065573Y295618D01*
X1065137Y293577D01*
X1065573Y291534D01*
X1066665Y290076D01*
X1068412Y289202D01*
X1069940Y288910D01*
G01X1083510Y288327D02*
X1091370Y306410D01*
G01X1100792Y296201D02*
X1102320Y298243D01*
X1103630Y299410D01*
X1105377Y299993D01*
X1106905Y299410D01*
X1107997Y298243D01*
X1108870Y296493D01*
X1109088Y294452D01*
X1108870Y292701D01*
X1107997Y290951D01*
X1106686Y289493D01*
X1105158Y288910D01*
X1103412Y289493D01*
X1101883Y291243D01*
X1101010Y293868D01*
X1100792Y296785D01*
X1101228Y300576D01*
X1101883Y302619D01*
X1102975Y304660D01*
X1104503Y306118D01*
X1106032Y306410D01*
X1107560Y305827D01*
X1108652Y304368D01*
G01X1122440Y288327D02*
X1122003Y288618D01*
Y289202D01*
X1122440Y289493D01*
X1122877Y289202D01*
Y288618D01*
X1122440Y288327D01*
G01X1135792Y303493D02*
X1137102Y305243D01*
X1138630Y306118D01*
X1140377Y306410D01*
X1142560Y305827D01*
X1144088Y304368D01*
X1144525Y302619D01*
X1144307Y300868D01*
X1143433Y299410D01*
X1139067Y296493D01*
X1137102Y294452D01*
X1135792Y291534D01*
X1135355Y288910D01*
X1144525D01*
G01X1236190Y341060D02*
Y323560D01*
G01X1231168Y341060D02*
X1241212D01*
G01X1253690Y323560D02*
Y331435D01*
X1249323Y341060D01*
G01X1258057D02*
X1253690Y331435D01*
G01X1266823Y323560D02*
Y341060D01*
X1272063D01*
X1273810Y340185D01*
X1275120Y338143D01*
X1275557Y335810D01*
X1275120Y333477D01*
X1274028Y331727D01*
X1272063Y330851D01*
X1266823D01*
G01X1293057Y323560D02*
X1284323D01*
Y341060D01*
X1293057D01*
G01X1289563Y332602D02*
X1284323D01*
G01X1248887Y288910D02*
Y306410D01*
X1253253D01*
X1255000Y305535D01*
X1256310Y304368D01*
X1257402Y302619D01*
X1258275Y300576D01*
X1258493Y297660D01*
X1258275Y294743D01*
X1257402Y292701D01*
X1256310Y290951D01*
X1255000Y289785D01*
X1253253Y288910D01*
X1248887D01*
G01X1266823D02*
Y306410D01*
X1272063D01*
X1273810Y305535D01*
X1275120Y303493D01*
X1275557Y301160D01*
X1275120Y298827D01*
X1274028Y297077D01*
X1272063Y296201D01*
X1266823D01*
G01X1336823Y323560D02*
Y341060D01*
X1342282D01*
X1344028Y340185D01*
X1345120Y339018D01*
X1345557Y336685D01*
X1345120Y334351D01*
X1343810Y332893D01*
X1342282Y332018D01*
X1336823D01*
G01X1342282D02*
X1345557Y323560D01*
G01X1355415Y331435D02*
X1362402D01*
X1361747Y333477D01*
X1360655Y334643D01*
X1359127Y335226D01*
X1357598Y334935D01*
X1356288Y334060D01*
X1355415Y332018D01*
X1354978Y330268D01*
Y328518D01*
X1355415Y326768D01*
X1356507Y325018D01*
X1357817Y323852D01*
X1359345Y323560D01*
X1360873Y324143D01*
X1362402Y325893D01*
G01X1374880Y323560D02*
Y338435D01*
X1375317Y339893D01*
X1376190Y340768D01*
X1377500Y341060D01*
X1378810Y340477D01*
X1379465Y339018D01*
G01X1376845Y334060D02*
X1372478D01*
G01X1393690Y322977D02*
X1393253Y323268D01*
Y323852D01*
X1393690Y324143D01*
X1394127Y323852D01*
Y323268D01*
X1393690Y322977D01*
G01X1424323Y323560D02*
Y341060D01*
X1429563D01*
X1431310Y340185D01*
X1432620Y338143D01*
X1433057Y335810D01*
X1432620Y333477D01*
X1431528Y331727D01*
X1429563Y330851D01*
X1424323D01*
G01X1446190Y323560D02*
Y341060D01*
G01X1467620Y323560D02*
Y335226D01*
G01Y333185D02*
X1466747Y334351D01*
X1465436Y334935D01*
X1463908Y335226D01*
X1462380Y334643D01*
X1461070Y333477D01*
X1460196Y331727D01*
X1459760Y329393D01*
X1460196Y327060D01*
X1461070Y325310D01*
X1462380Y324143D01*
X1463908Y323560D01*
X1465436Y323852D01*
X1466747Y324726D01*
X1467620Y325893D01*
G01X1477478Y323560D02*
Y335226D01*
G01Y332310D02*
X1478352Y333768D01*
X1479662Y334935D01*
X1481408Y335226D01*
X1482936Y334935D01*
X1484247Y333768D01*
X1484902Y331727D01*
Y323560D01*
G01X1495415Y331435D02*
X1502402D01*
X1501747Y333477D01*
X1500655Y334643D01*
X1499127Y335226D01*
X1497598Y334935D01*
X1496288Y334060D01*
X1495415Y332018D01*
X1494978Y330268D01*
Y328518D01*
X1495415Y326768D01*
X1496507Y325018D01*
X1497817Y323852D01*
X1499345Y323560D01*
X1500873Y324143D01*
X1502402Y325893D01*
G01X1406823Y306410D02*
Y288910D01*
X1415557D01*
G01X1424542Y303493D02*
X1425852Y305243D01*
X1427380Y306118D01*
X1429127Y306410D01*
X1431310Y305827D01*
X1432838Y304368D01*
X1433275Y302619D01*
X1433057Y300868D01*
X1432183Y299410D01*
X1427817Y296493D01*
X1425852Y294452D01*
X1424542Y291534D01*
X1424105Y288910D01*
X1433275D01*
G01X1616490Y300576D02*
Y288910D01*
G01Y305243D02*
X1616053Y305535D01*
Y306118D01*
X1616490Y306410D01*
X1616927Y306118D01*
Y305535D01*
X1616490Y305243D01*
G01X1630715Y290951D02*
X1631807Y289785D01*
X1633335Y288910D01*
X1634645D01*
X1635955Y289493D01*
X1636828Y290368D01*
X1637265Y291534D01*
X1637047Y293285D01*
X1636173Y294160D01*
X1632243Y295910D01*
X1631370Y297952D01*
X1631807Y299410D01*
X1632680Y300285D01*
X1633990Y300576D01*
X1635300Y300285D01*
X1636610Y299410D01*
G01X1663968Y288910D02*
Y306410D01*
X1674012Y288910D01*
Y306410D01*
G01X1686490Y288910D02*
X1684743Y289202D01*
X1683215Y290368D01*
X1681905Y292118D01*
X1681031Y294160D01*
X1680595Y296493D01*
Y298827D01*
X1681031Y301160D01*
X1681905Y303202D01*
X1683215Y304951D01*
X1684743Y306118D01*
X1686490Y306410D01*
X1688236Y306118D01*
X1689765Y304951D01*
X1691075Y303202D01*
X1691949Y301160D01*
X1692385Y298827D01*
Y296493D01*
X1691949Y294160D01*
X1691075Y292118D01*
X1689765Y290368D01*
X1688236Y289202D01*
X1686490Y288910D01*
G01X1703990Y306410D02*
Y288910D01*
G01X1698968Y306410D02*
X1709012D01*
G01X1735278Y300576D02*
Y292410D01*
X1736152Y290368D01*
X1737462Y289202D01*
X1738990Y288910D01*
X1740518Y289202D01*
X1741828Y290368D01*
X1742702Y292410D01*
G01Y288910D02*
Y300576D01*
G01X1753215Y290951D02*
X1754307Y289785D01*
X1755835Y288910D01*
X1757145D01*
X1758455Y289493D01*
X1759328Y290368D01*
X1759765Y291534D01*
X1759547Y293285D01*
X1758673Y294160D01*
X1754743Y295910D01*
X1753870Y297952D01*
X1754307Y299410D01*
X1755180Y300285D01*
X1756490Y300576D01*
X1757800Y300285D01*
X1759110Y299410D01*
G01X1770715Y296785D02*
X1777702D01*
X1777047Y298827D01*
X1775955Y299993D01*
X1774427Y300576D01*
X1772898Y300285D01*
X1771588Y299410D01*
X1770715Y297368D01*
X1770278Y295618D01*
Y293868D01*
X1770715Y292118D01*
X1771807Y290368D01*
X1773117Y289202D01*
X1774645Y288910D01*
X1776173Y289493D01*
X1777702Y291243D01*
G01X1795420Y306410D02*
Y288910D01*
G01Y291534D02*
X1794547Y290076D01*
X1793236Y289202D01*
X1791708Y288910D01*
X1789962Y289493D01*
X1788652Y290951D01*
X1787778Y292701D01*
X1787560Y294743D01*
X1787778Y296785D01*
X1788652Y298535D01*
X1789962Y299993D01*
X1791708Y300576D01*
X1793236Y300285D01*
X1794328Y299701D01*
X1795420Y298535D01*
G01X1541687Y322977D02*
X1551293Y335810D01*
G01X1546490Y338143D02*
Y320643D01*
G01X1551293Y322977D02*
X1541687Y335810D01*
G01X1539940Y329393D02*
X1553040D01*
G01X1578652D02*
X1584328D01*
G01X1611687Y323560D02*
Y341060D01*
X1616053D01*
X1617800Y340185D01*
X1619110Y339018D01*
X1620202Y337269D01*
X1621075Y335226D01*
X1621293Y332310D01*
X1621075Y329393D01*
X1620202Y327351D01*
X1619110Y325601D01*
X1617800Y324435D01*
X1616053Y323560D01*
X1611687D01*
G01X1630715Y331435D02*
X1637702D01*
X1637047Y333477D01*
X1635955Y334643D01*
X1634427Y335226D01*
X1632898Y334935D01*
X1631588Y334060D01*
X1630715Y332018D01*
X1630278Y330268D01*
Y328518D01*
X1630715Y326768D01*
X1631807Y325018D01*
X1633117Y323852D01*
X1634645Y323560D01*
X1636173Y324143D01*
X1637702Y325893D01*
G01X1647778Y323560D02*
Y335226D01*
G01Y332310D02*
X1648652Y333768D01*
X1649962Y334935D01*
X1651708Y335226D01*
X1653236Y334935D01*
X1654547Y333768D01*
X1655202Y331727D01*
Y323560D01*
G01X1668990D02*
X1667680Y323852D01*
X1666370Y325018D01*
X1665496Y327060D01*
X1665060Y329393D01*
X1665496Y331727D01*
X1666370Y333768D01*
X1667680Y334935D01*
X1668990Y335226D01*
X1670300Y334935D01*
X1671610Y333768D01*
X1672483Y331727D01*
X1672702Y329393D01*
X1672483Y327060D01*
X1671610Y325018D01*
X1670300Y323852D01*
X1668990Y323560D01*
G01X1686490Y341060D02*
Y323560D01*
G01X1683433Y335226D02*
X1689547D01*
G01X1700715Y331435D02*
X1707702D01*
X1707047Y333477D01*
X1705955Y334643D01*
X1704427Y335226D01*
X1702898Y334935D01*
X1701588Y334060D01*
X1700715Y332018D01*
X1700278Y330268D01*
Y328518D01*
X1700715Y326768D01*
X1701807Y325018D01*
X1703117Y323852D01*
X1704645Y323560D01*
X1706173Y324143D01*
X1707702Y325893D01*
G01X1718215Y325601D02*
X1719307Y324435D01*
X1720835Y323560D01*
X1722145D01*
X1723455Y324143D01*
X1724328Y325018D01*
X1724765Y326184D01*
X1724547Y327935D01*
X1723673Y328810D01*
X1719743Y330560D01*
X1718870Y332602D01*
X1719307Y334060D01*
X1720180Y334935D01*
X1721490Y335226D01*
X1722800Y334935D01*
X1724110Y334060D01*
G01X1756490Y341060D02*
Y323560D01*
G01X1753433Y335226D02*
X1759547D01*
G01X1770278Y323560D02*
Y341060D01*
G01Y332602D02*
X1771370Y334060D01*
X1772462Y334935D01*
X1774208Y335226D01*
X1775518Y334935D01*
X1777047Y333768D01*
X1777702Y332018D01*
Y323560D01*
G01X1795420D02*
Y335226D01*
G01Y333185D02*
X1794547Y334351D01*
X1793236Y334935D01*
X1791708Y335226D01*
X1790180Y334643D01*
X1788870Y333477D01*
X1787996Y331727D01*
X1787560Y329393D01*
X1787996Y327060D01*
X1788870Y325310D01*
X1790180Y324143D01*
X1791708Y323560D01*
X1793236Y323852D01*
X1794547Y324726D01*
X1795420Y325893D01*
G01X1808990Y341060D02*
Y323560D01*
G01X1805933Y335226D02*
X1812047D01*
G01X1843990Y341060D02*
Y323560D01*
G01X1840933Y335226D02*
X1847047D01*
G01X1857778Y323560D02*
Y341060D01*
G01Y332602D02*
X1858870Y334060D01*
X1859962Y334935D01*
X1861708Y335226D01*
X1863018Y334935D01*
X1864547Y333768D01*
X1865202Y332018D01*
Y323560D01*
G01X1878990Y335226D02*
Y323560D01*
G01Y339893D02*
X1878553Y340185D01*
Y340768D01*
X1878990Y341060D01*
X1879427Y340768D01*
Y340185D01*
X1878990Y339893D01*
G01X1893215Y325601D02*
X1894307Y324435D01*
X1895835Y323560D01*
X1897145D01*
X1898455Y324143D01*
X1899328Y325018D01*
X1899765Y326184D01*
X1899547Y327935D01*
X1898673Y328810D01*
X1894743Y330560D01*
X1893870Y332602D01*
X1894307Y334060D01*
X1895180Y334935D01*
X1896490Y335226D01*
X1897800Y334935D01*
X1899110Y334060D01*
G01X1928870Y341060D02*
X1934110D01*
G01X1931490D02*
Y323560D01*
G01X1928870D02*
X1934110D01*
G01X1942440D02*
Y335226D01*
G01Y332018D02*
X1943095Y333477D01*
X1944187Y334643D01*
X1945715Y335226D01*
X1947243Y334643D01*
X1948335Y333477D01*
X1948990Y332018D01*
Y323560D01*
G01Y332018D02*
X1949645Y333477D01*
X1950736Y334643D01*
X1952265Y335226D01*
X1953793Y334643D01*
X1954885Y333477D01*
X1955540Y331727D01*
Y323560D01*
G01X1962560Y317727D02*
Y335226D01*
G01Y332602D02*
X1963652Y334060D01*
X1964743Y334935D01*
X1966490Y335226D01*
X1968018Y334935D01*
X1969547Y333477D01*
X1970202Y331435D01*
X1970420Y329393D01*
X1970202Y327351D01*
X1969547Y325310D01*
X1968236Y324143D01*
X1966490Y323560D01*
X1964962Y323852D01*
X1963433Y324726D01*
X1962560Y325893D01*
G01X1980715Y331435D02*
X1987702D01*
X1987047Y333477D01*
X1985955Y334643D01*
X1984427Y335226D01*
X1982898Y334935D01*
X1981588Y334060D01*
X1980715Y332018D01*
X1980278Y330268D01*
Y328518D01*
X1980715Y326768D01*
X1981807Y325018D01*
X1983117Y323852D01*
X1984645Y323560D01*
X1986173Y324143D01*
X1987702Y325893D01*
G01X2005420Y341060D02*
Y323560D01*
G01Y326184D02*
X2004547Y324726D01*
X2003236Y323852D01*
X2001708Y323560D01*
X1999962Y324143D01*
X1998652Y325601D01*
X1997778Y327351D01*
X1997560Y329393D01*
X1997778Y331435D01*
X1998652Y333185D01*
X1999962Y334643D01*
X2001708Y335226D01*
X2003236Y334935D01*
X2004328Y334351D01*
X2005420Y333185D01*
G01X2022920Y323560D02*
Y335226D01*
G01Y333185D02*
X2022047Y334351D01*
X2020736Y334935D01*
X2019208Y335226D01*
X2017680Y334643D01*
X2016370Y333477D01*
X2015496Y331727D01*
X2015060Y329393D01*
X2015496Y327060D01*
X2016370Y325310D01*
X2017680Y324143D01*
X2019208Y323560D01*
X2020736Y323852D01*
X2022047Y324726D01*
X2022920Y325893D01*
G01X2032778Y323560D02*
Y335226D01*
G01Y332310D02*
X2033652Y333768D01*
X2034962Y334935D01*
X2036708Y335226D01*
X2038236Y334935D01*
X2039547Y333768D01*
X2040202Y331727D01*
Y323560D01*
G01X2057483Y333768D02*
X2055955Y334935D01*
X2054645Y335226D01*
X2052898Y334643D01*
X2051588Y333477D01*
X2050715Y331435D01*
X2050496Y329393D01*
X2050715Y327351D01*
X2051588Y325601D01*
X2052898Y324143D01*
X2054645Y323560D01*
X2056173Y324143D01*
X2057483Y325310D01*
G01X2068215Y331435D02*
X2075202D01*
X2074547Y333477D01*
X2073455Y334643D01*
X2071927Y335226D01*
X2070398Y334935D01*
X2069088Y334060D01*
X2068215Y332018D01*
X2067778Y330268D01*
Y328518D01*
X2068215Y326768D01*
X2069307Y325018D01*
X2070617Y323852D01*
X2072145Y323560D01*
X2073673Y324143D01*
X2075202Y325893D01*
G54D12*
G01X281488Y111389D02*
X277500D01*
G01X281614Y99578D02*
X275500D01*
G01X281530Y100736D02*
X275500D01*
G01X281530D02*
X275500D01*
G01X281614Y99578D02*
X275500D01*
G01X281488Y111389D02*
X277500D01*
G01X281641Y112547D02*
X277500D01*
G01X281641D02*
X277500D01*
G01X281614Y208240D02*
X275500D01*
G01X281530Y209398D02*
X275500D01*
G01X281530D02*
X275500D01*
G01X281614Y208240D02*
X275500D01*
G01X281488Y220051D02*
X277500D01*
G01X281641Y221209D02*
X277500D01*
G01X281641D02*
X277500D01*
G01X281488Y220051D02*
X277500D01*
G01X293596Y94831D02*
X290415D01*
G01X293596Y93673D02*
X290387D01*
G01X297817Y93083D02*
G03X293596Y94831I-4220J-4221D01*
G01X296998Y92264D02*
G03X293596Y93673I-3402J-3402D01*
G01X311450Y79450D02*
X297818Y93083D01*
G01X318396Y70866D02*
X296998Y92264D01*
G01X318396Y70866D02*
X296998Y92264D01*
G01X293596Y93673D02*
X290387D01*
G01X293596Y94831D02*
X290415D01*
G01X296998Y92264D02*
G03X293596Y93673I-3402J-3402D01*
G01X297817Y93083D02*
G03X293596Y94831I-4220J-4221D01*
G01X318396Y70866D02*
X296998Y92264D01*
G01X311450Y79450D02*
X297818Y93083D01*
G01X290342Y88925D02*
X290700D01*
G01X290314Y87767D02*
X291400D01*
G01X290314D02*
X291400D01*
G01X290342Y88925D02*
X290700D01*
G01X301095Y106642D02*
X290386D01*
G01X301095Y105484D02*
X290387D01*
G01X309053Y103346D02*
G03X301095Y106642I-7958J-7958D01*
G01X308234Y102527D02*
G03X301095Y105484I-7139J-7139D01*
G01D02*
X290387D01*
G01X301095Y106642D02*
X290386D01*
G01X308234Y102527D02*
G03X301095Y105484I-7139J-7139D01*
G01X309053Y103346D02*
G03X301095Y106642I-7958J-7958D01*
G01X301332Y178168D02*
G02X300600Y179936I1769J1768D01*
G01X300513Y177349D02*
G02X299442Y179936I2589J2587D01*
G01X309768Y169732D02*
X301332Y178168D01*
G01X308949Y168913D02*
X300513Y177349D01*
G01D02*
G02X299442Y179936I2589J2587D01*
G01X301332Y178168D02*
G02X300600Y179936I1769J1768D01*
G01X308949Y168913D02*
X300513Y177349D01*
G01X309768Y169732D02*
X301332Y178168D01*
G01X300600Y179936D02*
Y198522D01*
G01X299442Y179936D02*
Y198522D01*
G01Y179936D02*
Y198522D01*
G01X300600Y179936D02*
Y198522D01*
G01X295629Y203493D02*
X290415D01*
G01X295629Y202335D02*
X290387D01*
G01X300600Y198522D02*
G03X295629Y203493I-4971J0D01*
G01X299442Y198522D02*
G03X295629Y202335I-3813J0D01*
G01D02*
X290387D01*
G01X295629Y203493D02*
X290415D01*
G01X299442Y198522D02*
G03X295629Y202335I-3813J0D01*
G01X300600Y198522D02*
G03X295629Y203493I-4971J0D01*
G01X294268Y215304D02*
X290415D01*
G01X294268Y214146D02*
X290387D01*
G01X296036Y216036D02*
G02X294268Y215304I-1768J1769D01*
G01X296855Y215217D02*
G02X294268Y214146I-2587J2589D01*
G01X297268Y217268D02*
X296036Y216036D01*
G01X298087Y216449D02*
X296855Y215217D01*
G01X299036Y218000D02*
G03X297268Y217268I0J-2501D01*
G01X299036Y216842D02*
G03X298087Y216449I0J-1342D01*
G01X310622Y218000D02*
X299036D01*
G01X310622Y216842D02*
X299036D01*
G01X294268Y214146D02*
X290387D01*
G01X294268Y215304D02*
X290415D01*
G01X296855Y215217D02*
G02X294268Y214146I-2587J2589D01*
G01X296036Y216036D02*
G02X294268Y215304I-1768J1769D01*
G01X298087Y216449D02*
X296855Y215217D01*
G01X297268Y217268D02*
X296036Y216036D01*
G01X299036Y216842D02*
G03X298087Y216449I0J-1342D01*
G01X299036Y218000D02*
G03X297268Y217268I0J-2501D01*
G01X310622Y216842D02*
X299036D01*
G01X310622Y218000D02*
X299036D01*
G01X319215Y71685D02*
X311450Y79450D01*
G01X320983Y70953D02*
G02X319215Y71685I0J2501D01*
G01X320983Y69795D02*
G02X318396Y70866I0J3660D01*
G01X319215Y71685D02*
X311450Y79450D01*
G01X320983Y69795D02*
G02X318396Y70866I0J3660D01*
G01X320983Y70953D02*
G02X319215Y71685I0J2501D01*
G01X315631Y95131D02*
X308234Y102527D01*
G01X321877Y90523D02*
X309054Y103346D01*
G01X315631Y95131D02*
X308234Y102527D01*
G01X321058Y89704D02*
X315631Y95131D01*
G01D02*
X308234Y102527D01*
G01X321877Y90523D02*
X309054Y103346D01*
G01X321058Y89704D02*
X315631Y95131D01*
G01X321877Y90523D02*
X309054Y103346D01*
G01X317756Y112244D02*
G02X315596Y115469I7071J7072D01*
G01X316937Y111425D02*
G02X314526Y115023I7889J7893D01*
G01X320519Y109481D02*
X317756Y112244D01*
G01X319700Y108662D02*
X316937Y111425D01*
G01X322287Y107591D02*
G02X319700Y108662I0J3660D01*
G01X316937Y111425D02*
G02X314526Y115023I7889J7893D01*
G01X317756Y112244D02*
G02X315596Y115469I7071J7072D01*
G01X319700Y108662D02*
X316937Y111425D01*
G01X320519Y109481D02*
X317756Y112244D01*
G01X322287Y107591D02*
G02X319700Y108662I0J3660D01*
G01X309054Y103346D02*
X309053D01*
G01X309054D02*
X309053D01*
G01X311269Y125854D02*
G02X310500Y129700I9231J3846D01*
G01X310199Y125408D02*
G02X309342Y129700I10302J4289D01*
G01X315596Y115469D02*
X311269Y125854D01*
G01X314526Y115023D02*
X310199Y125408D01*
G01D02*
G02X309342Y129700I10302J4289D01*
G01X311269Y125854D02*
G02X310500Y129700I9231J3846D01*
G01X314526Y115023D02*
X310199Y125408D01*
G01X315596Y115469D02*
X311269Y125854D01*
G01X310500Y129700D02*
Y167964D01*
G01X309342Y129700D02*
Y167964D01*
G01Y129700D02*
Y167964D01*
G01X310500Y129700D02*
Y167964D01*
G01X320626Y159874D02*
X317501Y162999D01*
G01X319807Y159055D02*
X316682Y162180D01*
G01X322394Y157984D02*
G02X319807Y159055I0J3660D01*
G01D02*
X316682Y162180D01*
G01X320626Y159874D02*
X317501Y162999D01*
G01X322394Y157984D02*
G02X319807Y159055I0J3660D01*
G01X315698Y170440D02*
X305493Y180645D01*
G01X314879Y169621D02*
X304674Y179826D01*
G01X316769Y167853D02*
G03X315698Y170440I-3660J0D01*
G01X315611Y167853D02*
G03X314879Y169621I-2501J0D01*
G01X316769Y164767D02*
Y167853D01*
G01X315611Y164767D02*
Y167853D01*
G01X317501Y162999D02*
G02X316769Y164767I1769J1768D01*
G01X316682Y162180D02*
G02X315611Y164767I2589J2587D01*
G01X314879Y169621D02*
X304674Y179826D01*
G01X315698Y170440D02*
X305493Y180645D01*
G01X315611Y167853D02*
G03X314879Y169621I-2501J0D01*
G01X316769Y167853D02*
G03X315698Y170440I-3660J0D01*
G01X315611Y164767D02*
Y167853D01*
G01X316769Y164767D02*
Y167853D01*
G01X316682Y162180D02*
G02X315611Y164767I2589J2587D01*
G01X317501Y162999D02*
G02X316769Y164767I1769J1768D01*
G01X310500Y167964D02*
G03X309768Y169732I-2501J0D01*
G01X309342Y167964D02*
G03X308949Y168913I-1342J0D01*
G01X309342Y167964D02*
G03X308949Y168913I-1342J0D01*
G01X310500Y167964D02*
G03X309768Y169732I-2501J0D01*
G01X305493Y192355D02*
X313429Y200291D01*
G01X304674Y193174D02*
X312610Y201110D01*
G01X305100Y191406D02*
G02X305493Y192355I1342J0D01*
G01X303942Y191406D02*
G02X304674Y193174I2501J0D01*
G01X305100Y181594D02*
Y191406D01*
G01X303942Y181594D02*
Y191406D01*
G01X305493Y180645D02*
G02X305100Y181594I949J949D01*
G01X304674Y179826D02*
G02X303942Y181594I1769J1768D01*
G01X304674Y193174D02*
X312610Y201110D01*
G01X305493Y192355D02*
X313429Y200291D01*
G01X303942Y191406D02*
G02X304674Y193174I2501J0D01*
G01X305100Y191406D02*
G02X305493Y192355I1342J0D01*
G01X303942Y181594D02*
Y191406D01*
G01X305100Y181594D02*
Y191406D01*
G01X304674Y179826D02*
G02X303942Y181594I1769J1768D01*
G01X305493Y180645D02*
G02X305100Y181594I949J949D01*
G01X314500Y202878D02*
Y214122D01*
G01X313342Y202878D02*
Y214122D01*
G01X313429Y200291D02*
G03X314500Y202878I-2589J2587D01*
G01X312610Y201110D02*
G03X313342Y202878I-1769J1768D01*
G01D02*
Y214122D01*
G01X314500Y202878D02*
Y214122D01*
G01X312610Y201110D02*
G03X313342Y202878I-1769J1768D01*
G01X313429Y200291D02*
G03X314500Y202878I-2589J2587D01*
G01X313209Y216929D02*
G03X310622Y218000I-2587J-2589D01*
G01X312390Y216110D02*
G03X310622Y216842I-1768J-1769D01*
G01X313429Y216709D02*
X313209Y216929D01*
G01X312610Y215890D02*
X312390Y216110D01*
G01X314500Y214122D02*
G03X313429Y216709I-3660J0D01*
G01X313342Y214122D02*
G03X312610Y215890I-2501J0D01*
G01X312390Y216110D02*
G03X310622Y216842I-1768J-1769D01*
G01X313209Y216929D02*
G03X310622Y218000I-2587J-2589D01*
G01X312610Y215890D02*
X312390Y216110D01*
G01X313429Y216709D02*
X313209Y216929D01*
G01X313342Y214122D02*
G03X312610Y215890I-2501J0D01*
G01X314500Y214122D02*
G03X313429Y216709I-3660J0D01*
G01X322900Y70953D02*
X320983D01*
G01X322900Y69795D02*
X320983D01*
G01X322900D02*
X320983D01*
G01X322900Y70953D02*
X320983D01*
G01X323500Y89851D02*
G02X321877Y90523I0J2296D01*
G01X323500Y88693D02*
G02X321058Y89704I0J3455D01*
G01X323500Y88693D02*
G02X321058Y89704I0J3455D01*
G01X323500Y89851D02*
G02X321877Y90523I0J2296D01*
G01X322287Y108749D02*
G02X320519Y109481I0J2501D01*
G01X323500Y108749D02*
X322287D01*
G01X323500Y107591D02*
X322287D01*
G01Y108749D02*
G02X320519Y109481I0J2501D01*
G01X323500Y107591D02*
X322287D01*
G01X323500Y108749D02*
X322287D01*
G01X322394Y159142D02*
G02X320626Y159874I0J2501D01*
G01X322839Y159142D02*
X322394D01*
G01X322839Y157984D02*
X322394D01*
G01Y159142D02*
G02X320626Y159874I0J2501D01*
G01X322839Y157984D02*
X322394D01*
G01X322839Y159142D02*
X322394D01*
M02*
